# S9S_MB_2U (Grand Teton) — schematic netlist excerpt (pin names and nets, part order shuffled) for the footprints in the layout excerpt that follows; sources: Cadence DE-HDL packaged netlist, KiCad conversion of 03242023_DA0F0TMBIJ0_F0T_Motherboard_J_brd_V01_OCP.brd

R3040  Q_RES  1K 1% CHIP  pkg 0402LF  page 204 : A = P3V3_AUX ; B = IRQ_PCH_SCI_WHEA_N
PC207  Q_CAPP  270UF 16V 20% OSCON  pkg THLF  page 275 : A = SW_P12V_PVCCINFAON_CPU0_FLT ; B = GND
R2392  Q_RES  1K 1% CHIP  pkg 0402LF  page 274 : A = P3V3_AUX ; B = PVCCINFAON_CPU0_VR_FAULT

(kicad_pcb
	(version 20260206)
	(generator "pcbnew")
	(generator_version "10.0")
	(general
		(thickness 1.6)
		(legacy_teardrops no)
	)
	(paper "A4")
	(title_block
		(title "03242023_DA0F0TMBIJ0_F0T_Motherboard_J_brd_V01_OCP.brd")
		(comment 1 "Grand Teton / footprints 322-324 of 6105")
	)
	(layers
		(0 "F.Cu" signal "TOP")
		(4 "In1.Cu" signal "GND")
		(6 "In2.Cu" signal "IN1")
		(8 "In3.Cu" signal "GND1")
		(10 "In4.Cu" signal "IN2")
		(12 "In5.Cu" signal "GND2")
		(14 "In6.Cu" signal "IN3")
		(16 "In7.Cu" signal "GND3")
		(18 "In8.Cu" signal "VCC")
		(20 "In9.Cu" signal "VCC1")
		(22 "In10.Cu" signal "GND4")
		(24 "In11.Cu" signal "IN4")
		(26 "In12.Cu" signal "GND5")
		(28 "In13.Cu" signal "IN5")
		(30 "In14.Cu" signal "GND6")
		(32 "In15.Cu" signal "IN6")
		(34 "In16.Cu" signal "GND7")
		(2 "B.Cu" signal "BOTTOM")
		(9 "F.Adhes" user "F.Adhesive")
		(11 "B.Adhes" user "B.Adhesive")
		(13 "F.Paste" user "Package Geometry/Pastemask Top")
		(15 "B.Paste" user "Package Geometry/Pastemask Bottom")
		(5 "F.SilkS" user "Ref Des/Silkscreen Top")
		(7 "B.SilkS" user "Ref Des/Silkscreen Bottom")
		(1 "F.Mask" user "Board Geometry/Soldermask Top")
		(3 "B.Mask" user "Board Geometry/Soldermask Bottom")
		(17 "Dwgs.User" user "User.Drawings")
		(19 "Cmts.User" user "User.Comments")
		(21 "Eco1.User" user "User.Eco1")
		(23 "Eco2.User" user "User.Eco2")
		(25 "Edge.Cuts" user "Board Geometry/Outline")
		(27 "Margin" user)
		(31 "F.CrtYd" user "Package Geometry/Place Bound Top")
		(29 "B.CrtYd" user "Package Geometry/Place Bound Bottom")
		(35 "F.Fab" user "Ref Des/Assembly Top")
		(33 "B.Fab" user "Ref Des/Assembly Bottom")
	)
	(footprint ""
		(layer "F.Cu")
		(at 315.110622 -50.155348)
		(property "Reference" "R3040"
			(at 0 0 0)
			(layer "F.SilkS")
			(hide yes)
			(effects
				(font
					(size 1.27 1.27)
				)
			)
		)
		(property "Value" ""
			(at 0 0 0)
			(layer "F.Fab")
			(effects
				(font
					(size 1.27 1.27)
				)
			)
		)
		(duplicate_pad_numbers_are_jumpers no)
		(fp_line
			(start -0.7874 -0.4064)
			(end 0.7874 -0.4064)
			(stroke
				(width 0.1524)
				(type default)
			)
			(layer "F.SilkS")
		)
		(fp_line
			(start -0.7874 0.4064)
			(end -0.7874 -0.4064)
			(stroke
				(width 0.1524)
				(type default)
			)
			(layer "F.SilkS")
		)
		(fp_line
			(start 0.7874 -0.4064)
			(end 0.7874 0.4064)
			(stroke
				(width 0.1524)
				(type default)
			)
			(layer "F.SilkS")
		)
		(fp_line
			(start 0.7874 0.4064)
			(end -0.7874 0.4064)
			(stroke
				(width 0.1524)
				(type default)
			)
			(layer "F.SilkS")
		)
		(fp_line
			(start -0.67945 -0.305054)
			(end -0.12065 -0.305054)
			(stroke
				(width 0.1)
				(type default)
			)
			(layer "F.Fab")
		)
		(fp_line
			(start -0.67945 0.3048)
			(end -0.67945 -0.305054)
			(stroke
				(width 0.1)
				(type default)
			)
			(layer "F.Fab")
		)
		(fp_line
			(start -0.12065 -0.305054)
			(end -0.12065 -0.2794)
			(stroke
				(width 0.1)
				(type default)
			)
			(layer "F.Fab")
		)
		(fp_line
			(start -0.12065 -0.2794)
			(end 0.12065 -0.2794)
			(stroke
				(width 0.1)
				(type default)
			)
			(layer "F.Fab")
		)
		(fp_line
			(start -0.12065 0.2794)
			(end -0.12065 0.3048)
			(stroke
				(width 0.1)
				(type default)
			)
			(layer "F.Fab")
		)
		(fp_line
			(start -0.12065 0.3048)
			(end -0.67945 0.3048)
			(stroke
				(width 0.1)
				(type default)
			)
			(layer "F.Fab")
		)
		(fp_line
			(start 0.120396 0.2794)
			(end -0.12065 0.2794)
			(stroke
				(width 0.1)
				(type default)
			)
			(layer "F.Fab")
		)
		(fp_line
			(start 0.120396 0.3048)
			(end 0.120396 0.2794)
			(stroke
				(width 0.1)
				(type default)
			)
			(layer "F.Fab")
		)
		(fp_line
			(start 0.12065 -0.3048)
			(end 0.67945 -0.3048)
			(stroke
				(width 0.1)
				(type default)
			)
			(layer "F.Fab")
		)
		(fp_line
			(start 0.12065 -0.2794)
			(end 0.12065 -0.3048)
			(stroke
				(width 0.1)
				(type default)
			)
			(layer "F.Fab")
		)
		(fp_line
			(start 0.67945 -0.3048)
			(end 0.67945 0.3048)
			(stroke
				(width 0.1)
				(type default)
			)
			(layer "F.Fab")
		)
		(fp_line
			(start 0.67945 0.3048)
			(end 0.120396 0.3048)
			(stroke
				(width 0.1)
				(type default)
			)
			(layer "F.Fab")
		)
		(pad "1" smd circle
			(at -0.40005 0)
			(size 0 0)
			(layers "F.Cu" "F.Mask" "F.Paste")
			(net "P3V3_AUX")
		)
		(pad "2" smd circle
			(at 0.40005 0)
			(size 0 0)
			(layers "F.Cu" "F.Mask" "F.Paste")
			(net "IRQ_PCH_SCI_WHEA_N")
		)
	)
	(footprint ""
		(layer "F.Cu")
		(at 427.452028 -172.453808)
		(property "Reference" "PC207"
			(at 0 0 0)
			(layer "F.SilkS")
			(hide yes)
			(effects
				(font
					(size 1.27 1.27)
				)
			)
		)
		(property "Value" ""
			(at 0 0 0)
			(layer "F.Fab")
			(effects
				(font
					(size 1.27 1.27)
				)
			)
		)
		(duplicate_pad_numbers_are_jumpers no)
		(fp_line
			(start -3.400044 1.249934)
			(end 3.400044 1.249934)
			(stroke
				(width 0.1524)
				(type default)
			)
			(layer "F.SilkS")
		)
		(fp_circle
			(center 0 1.249934)
			(end 3.400044 1.249934)
			(stroke
				(width 0.1524)
				(type default)
			)
			(fill no)
			(layer "F.SilkS")
		)
		(fp_poly
			(pts
				(arc
					(start -3.400044 1.249934)
					(mid 0 4.649978)
					(end 3.400044 1.249934)
				)
			)
			(stroke
				(width 0)
				(type default)
			)
			(fill yes)
			(layer "F.SilkS")
		)
		(fp_circle
			(center 0 1.249934)
			(end 3.400044 1.249934)
			(stroke
				(width 0.1)
				(type default)
			)
			(fill no)
			(layer "F.Fab")
		)
		(pad "1" thru_hole rect
			(at 0 0)
			(size 1.524 1.524)
			(drill 1.016)
			(layers "*.Cu" "*.Mask")
			(remove_unused_layers no)
			(net "SW_P12V_PVCCINFAON_CPU0_FLT")
			(clearance 0)
			(padstack
				(mode front_inner_back)
				(layer "Inner"
					(shape circle)
					(size 1.524 1.524)
					(clearance 0)
				)
				(layer "B.Cu"
					(shape rect)
					(size 1.524 1.524)
					(clearance 0)
				)
			)
		)
		(pad "2" thru_hole circle
			(at 0 2.500122)
			(size 1.524 1.524)
			(drill 1.016)
			(layers "*.Cu" "*.Mask")
			(remove_unused_layers no)
			(net "GND")
			(clearance 0)
		)
	)
	(footprint ""
		(layer "F.Cu")
		(at 420.682166 -138.333988)
		(property "Reference" "R2392"
			(at 0 0 0)
			(layer "F.SilkS")
			(hide yes)
			(effects
				(font
					(size 1.27 1.27)
				)
			)
		)
		(property "Value" ""
			(at 0 0 0)
			(layer "F.Fab")
			(effects
				(font
					(size 1.27 1.27)
				)
			)
		)
		(duplicate_pad_numbers_are_jumpers no)
		(fp_line
			(start -0.7874 -0.4064)
			(end 0.7874 -0.4064)
			(stroke
				(width 0.1524)
				(type default)
			)
			(layer "F.SilkS")
		)
		(fp_line
			(start -0.7874 0.4064)
			(end -0.7874 -0.4064)
			(stroke
				(width 0.1524)
				(type default)
			)
			(layer "F.SilkS")
		)
		(fp_line
			(start 0.7874 -0.4064)
			(end 0.7874 0.4064)
			(stroke
				(width 0.1524)
				(type default)
			)
			(layer "F.SilkS")
		)
		(fp_line
			(start 0.7874 0.4064)
			(end -0.7874 0.4064)
			(stroke
				(width 0.1524)
				(type default)
			)
			(layer "F.SilkS")
		)
		(fp_line
			(start -0.67945 -0.305054)
			(end -0.12065 -0.305054)
			(stroke
				(width 0.1)
				(type default)
			)
			(layer "F.Fab")
		)
		(fp_line
			(start -0.67945 0.3048)
			(end -0.67945 -0.305054)
			(stroke
				(width 0.1)
				(type default)
			)
			(layer "F.Fab")
		)
		(fp_line
			(start -0.12065 -0.305054)
			(end -0.12065 -0.2794)
			(stroke
				(width 0.1)
				(type default)
			)
			(layer "F.Fab")
		)
		(fp_line
			(start -0.12065 -0.2794)
			(end 0.12065 -0.2794)
			(stroke
				(width 0.1)
				(type default)
			)
			(layer "F.Fab")
		)
		(fp_line
			(start -0.12065 0.2794)
			(end -0.12065 0.3048)
			(stroke
				(width 0.1)
				(type default)
			)
			(layer "F.Fab")
		)
		(fp_line
			(start -0.12065 0.3048)
			(end -0.67945 0.3048)
			(stroke
				(width 0.1)
				(type default)
			)
			(layer "F.Fab")
		)
		(fp_line
			(start 0.120396 0.2794)
			(end -0.12065 0.2794)
			(stroke
				(width 0.1)
				(type default)
			)
			(layer "F.Fab")
		)
		(fp_line
			(start 0.120396 0.3048)
			(end 0.120396 0.2794)
			(stroke
				(width 0.1)
				(type default)
			)
			(layer "F.Fab")
		)
		(fp_line
			(start 0.12065 -0.3048)
			(end 0.67945 -0.3048)
			(stroke
				(width 0.1)
				(type default)
			)
			(layer "F.Fab")
		)
		(fp_line
			(start 0.12065 -0.2794)
			(end 0.12065 -0.3048)
			(stroke
				(width 0.1)
				(type default)
			)
			(layer "F.Fab")
		)
		(fp_line
			(start 0.67945 -0.3048)
			(end 0.67945 0.3048)
			(stroke
				(width 0.1)
				(type default)
			)
			(layer "F.Fab")
		)
		(fp_line
			(start 0.67945 0.3048)
			(end 0.120396 0.3048)
			(stroke
				(width 0.1)
				(type default)
			)
			(layer "F.Fab")
		)
		(pad "1" smd circle
			(at -0.40005 0)
			(size 0 0)
			(layers "F.Cu" "F.Mask" "F.Paste")
			(net "P3V3_AUX")
		)
		(pad "2" smd circle
			(at 0.40005 0)
			(size 0 0)
			(layers "F.Cu" "F.Mask" "F.Paste")
			(net "PVCCINFAON_CPU0_VR_FAULT")
		)
	)
)
